(kicad_pcb
	(version 20260206)
	(generator "pcbnew")
	(generator_version "10.0")
	(general
		(thickness 1.6)
		(legacy_teardrops no)
	)
	(paper "A4")
	(title_block
		(title "01162023_DA0F0TEBIF0_F0T_Expander_BD_F_brd_V02_OCP.brd")
		(comment 1 "Grand Teton / footprints 3833-3840 of 9728")
	)
	(layers
		(0 "F.Cu" signal "TOP")
		(4 "In1.Cu" signal "GND")
		(6 "In2.Cu" signal "VCC")
		(8 "In3.Cu" signal "VCC1")
		(10 "In4.Cu" signal "GND1")
		(12 "In5.Cu" signal "IN1")
		(14 "In6.Cu" signal "GND2")
		(16 "In7.Cu" signal "IN2")
		(18 "In8.Cu" signal "GND3")
		(20 "In9.Cu" signal "IN3")
		(22 "In10.Cu" signal "GND4")
		(24 "In11.Cu" signal "IN4")
		(26 "In12.Cu" signal "GND5")
		(28 "In13.Cu" signal "IN5")
		(30 "In14.Cu" signal "GND6")
		(32 "In15.Cu" signal "IN6")
		(34 "In16.Cu" signal "GND7")
		(2 "B.Cu" signal "BOTTOM")
		(9 "F.Adhes" user "F.Adhesive")
		(11 "B.Adhes" user "B.Adhesive")
		(13 "F.Paste" user "Package Geometry/Pastemask Top")
		(15 "B.Paste" user "Package Geometry/Pastemask Bottom")
		(5 "F.SilkS" user "Ref Des/Silkscreen Top")
		(7 "B.SilkS" user "Ref Des/Silkscreen Bottom")
		(1 "F.Mask" user "Board Geometry/Soldermask Top")
		(3 "B.Mask" user "Board Geometry/Soldermask Bottom")
		(17 "Dwgs.User" user "User.Drawings")
		(19 "Cmts.User" user "User.Comments")
		(21 "Eco1.User" user "User.Eco1")
		(23 "Eco2.User" user "User.Eco2")
		(25 "Edge.Cuts" user "Board Geometry/Outline")
		(27 "Margin" user)
		(31 "F.CrtYd" user "Package Geometry/Place Bound Top")
		(29 "B.CrtYd" user "Package Geometry/Place Bound Bottom")
		(35 "F.Fab" user "Ref Des/Assembly Top")
		(33 "B.Fab" user "Ref Des/Assembly Bottom")
	)
	(footprint ""
		(layer "F.Cu")
		(at 101.553264 -242.480338 -90)
		(property "Reference" "C830"
			(at 0 0 270)
			(layer "F.SilkS")
			(hide yes)
			(effects
				(font
					(size 1.27 1.27)
				)
			)
		)
		(property "Value" ""
			(at 0 0 270)
			(layer "F.Fab")
			(effects
				(font
					(size 1.27 1.27)
				)
			)
		)
		(duplicate_pad_numbers_are_jumpers no)
		(fp_line
			(start -0.7874 0.4064)
			(end -0.7874 -0.4064)
			(stroke
				(width 0.1524)
				(type default)
			)
			(layer "F.SilkS")
		)
		(fp_line
			(start 0.7874 0.4064)
			(end -0.7874 0.4064)
			(stroke
				(width 0.1524)
				(type default)
			)
			(layer "F.SilkS")
		)
		(fp_line
			(start -0.7874 -0.4064)
			(end 0.7874 -0.4064)
			(stroke
				(width 0.1524)
				(type default)
			)
			(layer "F.SilkS")
		)
		(fp_line
			(start 0.7874 -0.4064)
			(end 0.7874 0.4064)
			(stroke
				(width 0.1524)
				(type default)
			)
			(layer "F.SilkS")
		)
		(fp_line
			(start -0.67945 0.3048)
			(end -0.67945 -0.305054)
			(stroke
				(width 0.1)
				(type default)
			)
			(layer "F.Fab")
		)
		(fp_line
			(start -0.12065 0.3048)
			(end -0.67945 0.3048)
			(stroke
				(width 0.1)
				(type default)
			)
			(layer "F.Fab")
		)
		(fp_line
			(start 0.120396 0.3048)
			(end 0.120396 0.2794)
			(stroke
				(width 0.1)
				(type default)
			)
			(layer "F.Fab")
		)
		(fp_line
			(start 0.67945 0.3048)
			(end 0.120396 0.3048)
			(stroke
				(width 0.1)
				(type default)
			)
			(layer "F.Fab")
		)
		(fp_line
			(start -0.12065 0.2794)
			(end -0.12065 0.3048)
			(stroke
				(width 0.1)
				(type default)
			)
			(layer "F.Fab")
		)
		(fp_line
			(start 0.120396 0.2794)
			(end -0.12065 0.2794)
			(stroke
				(width 0.1)
				(type default)
			)
			(layer "F.Fab")
		)
		(fp_line
			(start -0.12065 -0.2794)
			(end 0.12065 -0.2794)
			(stroke
				(width 0.1)
				(type default)
			)
			(layer "F.Fab")
		)
		(fp_line
			(start 0.12065 -0.2794)
			(end 0.12065 -0.3048)
			(stroke
				(width 0.1)
				(type default)
			)
			(layer "F.Fab")
		)
		(fp_line
			(start 0.12065 -0.3048)
			(end 0.67945 -0.3048)
			(stroke
				(width 0.1)
				(type default)
			)
			(layer "F.Fab")
		)
		(fp_line
			(start 0.67945 -0.3048)
			(end 0.67945 0.3048)
			(stroke
				(width 0.1)
				(type default)
			)
			(layer "F.Fab")
		)
		(fp_line
			(start -0.67945 -0.305054)
			(end -0.12065 -0.305054)
			(stroke
				(width 0.1)
				(type default)
			)
			(layer "F.Fab")
		)
		(fp_line
			(start -0.12065 -0.305054)
			(end -0.12065 -0.2794)
			(stroke
				(width 0.1)
				(type default)
			)
			(layer "F.Fab")
		)
		(pad "1" smd circle
			(at -0.40005 0 270)
			(size 0 0)
			(layers "F.Cu" "F.Mask" "F.Paste")
			(net "P1V8_PEX_R")
		)
		(pad "2" smd circle
			(at 0.40005 0 270)
			(size 0 0)
			(layers "F.Cu" "F.Mask" "F.Paste")
			(net "GND")
		)
	)
	(footprint ""
		(layer "F.Cu")
		(at 136.708388 -356.244906 90)
		(property "Reference" "C2249"
			(at 0 0 90)
			(layer "F.SilkS")
			(hide yes)
			(effects
				(font
					(size 1.27 1.27)
				)
			)
		)
		(property "Value" ""
			(at 0 0 90)
			(layer "F.Fab")
			(effects
				(font
					(size 1.27 1.27)
				)
			)
		)
		(duplicate_pad_numbers_are_jumpers no)
		(fp_line
			(start 0.299974 -0.150114)
			(end 0.299974 0.150114)
			(stroke
				(width 0.1)
				(type default)
			)
			(layer "F.Fab")
		)
		(fp_line
			(start -0.299974 -0.150114)
			(end 0.299974 -0.150114)
			(stroke
				(width 0.1)
				(type default)
			)
			(layer "F.Fab")
		)
		(fp_line
			(start 0.299974 0.150114)
			(end -0.299974 0.150114)
			(stroke
				(width 0.1)
				(type default)
			)
			(layer "F.Fab")
		)
		(fp_line
			(start -0.299974 0.150114)
			(end -0.299974 -0.150114)
			(stroke
				(width 0.1)
				(type default)
			)
			(layer "F.Fab")
		)
		(pad "1" smd rect
			(at -0.2667 0 90)
			(size 0.3048 0.381)
			(layers "F.Cu" "F.Mask" "F.Paste")
			(net "P5E_PEX1_STN5_TX_DP<92>")
		)
		(pad "2" smd rect
			(at 0.2667 0 90)
			(size 0.3048 0.381)
			(layers "F.Cu" "F.Mask" "F.Paste")
			(net "P5E_PEX1_STN5_TX_C_DP<92>")
		)
	)
	(footprint ""
		(layer "F.Cu")
		(at 44.638722 -22.867366 90)
		(property "Reference" "C3885"
			(at 0 0 90)
			(layer "F.SilkS")
			(hide yes)
			(effects
				(font
					(size 1.27 1.27)
				)
			)
		)
		(property "Value" ""
			(at 0 0 90)
			(layer "F.Fab")
			(effects
				(font
					(size 1.27 1.27)
				)
			)
		)
		(duplicate_pad_numbers_are_jumpers no)
		(fp_line
			(start 0.7874 -0.4064)
			(end 0.7874 0.4064)
			(stroke
				(width 0.1524)
				(type default)
			)
			(layer "F.SilkS")
		)
		(fp_line
			(start -0.7874 -0.4064)
			(end 0.7874 -0.4064)
			(stroke
				(width 0.1524)
				(type default)
			)
			(layer "F.SilkS")
		)
		(fp_line
			(start 0.7874 0.4064)
			(end -0.7874 0.4064)
			(stroke
				(width 0.1524)
				(type default)
			)
			(layer "F.SilkS")
		)
		(fp_line
			(start -0.7874 0.4064)
			(end -0.7874 -0.4064)
			(stroke
				(width 0.1524)
				(type default)
			)
			(layer "F.SilkS")
		)
		(fp_line
			(start -0.12065 -0.305054)
			(end -0.12065 -0.2794)
			(stroke
				(width 0.1)
				(type default)
			)
			(layer "F.Fab")
		)
		(fp_line
			(start -0.67945 -0.305054)
			(end -0.12065 -0.305054)
			(stroke
				(width 0.1)
				(type default)
			)
			(layer "F.Fab")
		)
		(fp_line
			(start 0.67945 -0.3048)
			(end 0.67945 0.3048)
			(stroke
				(width 0.1)
				(type default)
			)
			(layer "F.Fab")
		)
		(fp_line
			(start 0.12065 -0.3048)
			(end 0.67945 -0.3048)
			(stroke
				(width 0.1)
				(type default)
			)
			(layer "F.Fab")
		)
		(fp_line
			(start 0.12065 -0.2794)
			(end 0.12065 -0.3048)
			(stroke
				(width 0.1)
				(type default)
			)
			(layer "F.Fab")
		)
		(fp_line
			(start -0.12065 -0.2794)
			(end 0.12065 -0.2794)
			(stroke
				(width 0.1)
				(type default)
			)
			(layer "F.Fab")
		)
		(fp_line
			(start 0.120396 0.2794)
			(end -0.12065 0.2794)
			(stroke
				(width 0.1)
				(type default)
			)
			(layer "F.Fab")
		)
		(fp_line
			(start -0.12065 0.2794)
			(end -0.12065 0.3048)
			(stroke
				(width 0.1)
				(type default)
			)
			(layer "F.Fab")
		)
		(fp_line
			(start 0.67945 0.3048)
			(end 0.120396 0.3048)
			(stroke
				(width 0.1)
				(type default)
			)
			(layer "F.Fab")
		)
		(fp_line
			(start 0.120396 0.3048)
			(end 0.120396 0.2794)
			(stroke
				(width 0.1)
				(type default)
			)
			(layer "F.Fab")
		)
		(fp_line
			(start -0.12065 0.3048)
			(end -0.67945 0.3048)
			(stroke
				(width 0.1)
				(type default)
			)
			(layer "F.Fab")
		)
		(fp_line
			(start -0.67945 0.3048)
			(end -0.67945 -0.305054)
			(stroke
				(width 0.1)
				(type default)
			)
			(layer "F.Fab")
		)
		(pad "1" smd circle
			(at -0.40005 0 90)
			(size 0 0)
			(layers "F.Cu" "F.Mask" "F.Paste")
			(net "P12V_SSD1")
		)
		(pad "2" smd circle
			(at 0.40005 0 90)
			(size 0 0)
			(layers "F.Cu" "F.Mask" "F.Paste")
			(net "GND")
		)
	)
	(footprint ""
		(layer "F.Cu")
		(at 258.22529 -77.279754 -90)
		(property "Reference" "R1081"
			(at 0 0 270)
			(layer "F.SilkS")
			(hide yes)
			(effects
				(font
					(size 1.27 1.27)
				)
			)
		)
		(property "Value" ""
			(at 0 0 270)
			(layer "F.Fab")
			(effects
				(font
					(size 1.27 1.27)
				)
			)
		)
		(duplicate_pad_numbers_are_jumpers no)
		(fp_line
			(start -0.7874 0.4064)
			(end -0.7874 -0.4064)
			(stroke
				(width 0.1524)
				(type default)
			)
			(layer "F.SilkS")
		)
		(fp_line
			(start 0.7874 0.4064)
			(end -0.7874 0.4064)
			(stroke
				(width 0.1524)
				(type default)
			)
			(layer "F.SilkS")
		)
		(fp_line
			(start -0.7874 -0.4064)
			(end 0.7874 -0.4064)
			(stroke
				(width 0.1524)
				(type default)
			)
			(layer "F.SilkS")
		)
		(fp_line
			(start 0.7874 -0.4064)
			(end 0.7874 0.4064)
			(stroke
				(width 0.1524)
				(type default)
			)
			(layer "F.SilkS")
		)
		(fp_line
			(start -0.67945 0.3048)
			(end -0.67945 -0.305054)
			(stroke
				(width 0.1)
				(type default)
			)
			(layer "F.Fab")
		)
		(fp_line
			(start -0.12065 0.3048)
			(end -0.67945 0.3048)
			(stroke
				(width 0.1)
				(type default)
			)
			(layer "F.Fab")
		)
		(fp_line
			(start 0.120396 0.3048)
			(end 0.120396 0.2794)
			(stroke
				(width 0.1)
				(type default)
			)
			(layer "F.Fab")
		)
		(fp_line
			(start 0.67945 0.3048)
			(end 0.120396 0.3048)
			(stroke
				(width 0.1)
				(type default)
			)
			(layer "F.Fab")
		)
		(fp_line
			(start -0.12065 0.2794)
			(end -0.12065 0.3048)
			(stroke
				(width 0.1)
				(type default)
			)
			(layer "F.Fab")
		)
		(fp_line
			(start 0.120396 0.2794)
			(end -0.12065 0.2794)
			(stroke
				(width 0.1)
				(type default)
			)
			(layer "F.Fab")
		)
		(fp_line
			(start -0.12065 -0.2794)
			(end 0.12065 -0.2794)
			(stroke
				(width 0.1)
				(type default)
			)
			(layer "F.Fab")
		)
		(fp_line
			(start 0.12065 -0.2794)
			(end 0.12065 -0.3048)
			(stroke
				(width 0.1)
				(type default)
			)
			(layer "F.Fab")
		)
		(fp_line
			(start 0.12065 -0.3048)
			(end 0.67945 -0.3048)
			(stroke
				(width 0.1)
				(type default)
			)
			(layer "F.Fab")
		)
		(fp_line
			(start 0.67945 -0.3048)
			(end 0.67945 0.3048)
			(stroke
				(width 0.1)
				(type default)
			)
			(layer "F.Fab")
		)
		(fp_line
			(start -0.67945 -0.305054)
			(end -0.12065 -0.305054)
			(stroke
				(width 0.1)
				(type default)
			)
			(layer "F.Fab")
		)
		(fp_line
			(start -0.12065 -0.305054)
			(end -0.12065 -0.2794)
			(stroke
				(width 0.1)
				(type default)
			)
			(layer "F.Fab")
		)
		(pad "1" smd circle
			(at -0.40005 0 270)
			(size 0 0)
			(layers "F.Cu" "F.Mask" "F.Paste")
			(net "CLK_GEN_CK440_OE6_N")
		)
		(pad "2" smd circle
			(at 0.40005 0 270)
			(size 0 0)
			(layers "F.Cu" "F.Mask" "F.Paste")
			(net "P3V3")
		)
	)
	(footprint ""
		(layer "F.Cu")
		(at 169.293032 -343.952322 90)
		(property "Reference" "C397"
			(at 0 0 90)
			(layer "F.SilkS")
			(hide yes)
			(effects
				(font
					(size 1.27 1.27)
				)
			)
		)
		(property "Value" ""
			(at 0 0 90)
			(layer "F.Fab")
			(effects
				(font
					(size 1.27 1.27)
				)
			)
		)
		(duplicate_pad_numbers_are_jumpers no)
		(fp_line
			(start 0.299974 -0.150114)
			(end 0.299974 0.150114)
			(stroke
				(width 0.1)
				(type default)
			)
			(layer "F.Fab")
		)
		(fp_line
			(start -0.299974 -0.150114)
			(end 0.299974 -0.150114)
			(stroke
				(width 0.1)
				(type default)
			)
			(layer "F.Fab")
		)
		(fp_line
			(start 0.299974 0.150114)
			(end -0.299974 0.150114)
			(stroke
				(width 0.1)
				(type default)
			)
			(layer "F.Fab")
		)
		(fp_line
			(start -0.299974 0.150114)
			(end -0.299974 -0.150114)
			(stroke
				(width 0.1)
				(type default)
			)
			(layer "F.Fab")
		)
		(pad "1" smd rect
			(at -0.2667 0 90)
			(size 0.3048 0.381)
			(layers "F.Cu" "F.Mask" "F.Paste")
			(net "P5E_PEX1_STN7_TX_DN<115>")
		)
		(pad "2" smd rect
			(at 0.2667 0 90)
			(size 0.3048 0.381)
			(layers "F.Cu" "F.Mask" "F.Paste")
			(net "P5E_PEX1_STN7_TX_C_DN<115>")
		)
	)
	(footprint ""
		(layer "F.Cu")
		(at 386.90804 -157.3784 180)
		(property "Reference" "R318"
			(at 0 0 180)
			(layer "F.SilkS")
			(hide yes)
			(effects
				(font
					(size 1.27 1.27)
				)
			)
		)
		(property "Value" ""
			(at 0 0 180)
			(layer "F.Fab")
			(effects
				(font
					(size 1.27 1.27)
				)
			)
		)
		(duplicate_pad_numbers_are_jumpers no)
		(fp_line
			(start 0.7874 0.4064)
			(end -0.7874 0.4064)
			(stroke
				(width 0.1524)
				(type default)
			)
			(layer "F.SilkS")
		)
		(fp_line
			(start 0.7874 -0.4064)
			(end 0.7874 0.4064)
			(stroke
				(width 0.1524)
				(type default)
			)
			(layer "F.SilkS")
		)
		(fp_line
			(start -0.7874 0.4064)
			(end -0.7874 -0.4064)
			(stroke
				(width 0.1524)
				(type default)
			)
			(layer "F.SilkS")
		)
		(fp_line
			(start -0.7874 -0.4064)
			(end 0.7874 -0.4064)
			(stroke
				(width 0.1524)
				(type default)
			)
			(layer "F.SilkS")
		)
		(fp_line
			(start 0.67945 0.3048)
			(end 0.120396 0.3048)
			(stroke
				(width 0.1)
				(type default)
			)
			(layer "F.Fab")
		)
		(fp_line
			(start 0.67945 -0.3048)
			(end 0.67945 0.3048)
			(stroke
				(width 0.1)
				(type default)
			)
			(layer "F.Fab")
		)
		(fp_line
			(start 0.12065 -0.2794)
			(end 0.12065 -0.3048)
			(stroke
				(width 0.1)
				(type default)
			)
			(layer "F.Fab")
		)
		(fp_line
			(start 0.12065 -0.3048)
			(end 0.67945 -0.3048)
			(stroke
				(width 0.1)
				(type default)
			)
			(layer "F.Fab")
		)
		(fp_line
			(start 0.120396 0.3048)
			(end 0.120396 0.2794)
			(stroke
				(width 0.1)
				(type default)
			)
			(layer "F.Fab")
		)
		(fp_line
			(start 0.120396 0.2794)
			(end -0.12065 0.2794)
			(stroke
				(width 0.1)
				(type default)
			)
			(layer "F.Fab")
		)
		(fp_line
			(start -0.12065 0.3048)
			(end -0.67945 0.3048)
			(stroke
				(width 0.1)
				(type default)
			)
			(layer "F.Fab")
		)
		(fp_line
			(start -0.12065 0.2794)
			(end -0.12065 0.3048)
			(stroke
				(width 0.1)
				(type default)
			)
			(layer "F.Fab")
		)
		(fp_line
			(start -0.12065 -0.2794)
			(end 0.12065 -0.2794)
			(stroke
				(width 0.1)
				(type default)
			)
			(layer "F.Fab")
		)
		(fp_line
			(start -0.12065 -0.305054)
			(end -0.12065 -0.2794)
			(stroke
				(width 0.1)
				(type default)
			)
			(layer "F.Fab")
		)
		(fp_line
			(start -0.67945 0.3048)
			(end -0.67945 -0.305054)
			(stroke
				(width 0.1)
				(type default)
			)
			(layer "F.Fab")
		)
		(fp_line
			(start -0.67945 -0.305054)
			(end -0.12065 -0.305054)
			(stroke
				(width 0.1)
				(type default)
			)
			(layer "F.Fab")
		)
		(pad "1" smd circle
			(at -0.40005 0 180)
			(size 0 0)
			(layers "F.Cu" "F.Mask" "F.Paste")
			(net "NIC6_DATA_IN")
		)
		(pad "2" smd circle
			(at 0.40005 0 180)
			(size 0 0)
			(layers "F.Cu" "F.Mask" "F.Paste")
			(net "P3V3_NIC6")
		)
	)
	(footprint ""
		(layer "F.Cu")
		(at 112.311942 -114.960654)
		(property "Reference" "PR6878"
			(at 0 0 0)
			(layer "F.SilkS")
			(hide yes)
			(effects
				(font
					(size 1.27 1.27)
				)
			)
		)
		(property "Value" ""
			(at 0 0 0)
			(layer "F.Fab")
			(effects
				(font
					(size 1.27 1.27)
				)
			)
		)
		(duplicate_pad_numbers_are_jumpers no)
		(fp_line
			(start -0.7874 -0.4064)
			(end 0.7874 -0.4064)
			(stroke
				(width 0.1524)
				(type default)
			)
			(layer "F.SilkS")
		)
		(fp_line
			(start -0.7874 0.4064)
			(end -0.7874 -0.4064)
			(stroke
				(width 0.1524)
				(type default)
			)
			(layer "F.SilkS")
		)
		(fp_line
			(start 0.7874 -0.4064)
			(end 0.7874 0.4064)
			(stroke
				(width 0.1524)
				(type default)
			)
			(layer "F.SilkS")
		)
		(fp_line
			(start 0.7874 0.4064)
			(end -0.7874 0.4064)
			(stroke
				(width 0.1524)
				(type default)
			)
			(layer "F.SilkS")
		)
		(fp_line
			(start -0.67945 -0.305054)
			(end -0.12065 -0.305054)
			(stroke
				(width 0.1)
				(type default)
			)
			(layer "F.Fab")
		)
		(fp_line
			(start -0.67945 0.3048)
			(end -0.67945 -0.305054)
			(stroke
				(width 0.1)
				(type default)
			)
			(layer "F.Fab")
		)
		(fp_line
			(start -0.12065 -0.305054)
			(end -0.12065 -0.2794)
			(stroke
				(width 0.1)
				(type default)
			)
			(layer "F.Fab")
		)
		(fp_line
			(start -0.12065 -0.2794)
			(end 0.12065 -0.2794)
			(stroke
				(width 0.1)
				(type default)
			)
			(layer "F.Fab")
		)
		(fp_line
			(start -0.12065 0.2794)
			(end -0.12065 0.3048)
			(stroke
				(width 0.1)
				(type default)
			)
			(layer "F.Fab")
		)
		(fp_line
			(start -0.12065 0.3048)
			(end -0.67945 0.3048)
			(stroke
				(width 0.1)
				(type default)
			)
			(layer "F.Fab")
		)
		(fp_line
			(start 0.120396 0.2794)
			(end -0.12065 0.2794)
			(stroke
				(width 0.1)
				(type default)
			)
			(layer "F.Fab")
		)
		(fp_line
			(start 0.120396 0.3048)
			(end 0.120396 0.2794)
			(stroke
				(width 0.1)
				(type default)
			)
			(layer "F.Fab")
		)
		(fp_line
			(start 0.12065 -0.3048)
			(end 0.67945 -0.3048)
			(stroke
				(width 0.1)
				(type default)
			)
			(layer "F.Fab")
		)
		(fp_line
			(start 0.12065 -0.2794)
			(end 0.12065 -0.3048)
			(stroke
				(width 0.1)
				(type default)
			)
			(layer "F.Fab")
		)
		(fp_line
			(start 0.67945 -0.3048)
			(end 0.67945 0.3048)
			(stroke
				(width 0.1)
				(type default)
			)
			(layer "F.Fab")
		)
		(fp_line
			(start 0.67945 0.3048)
			(end 0.120396 0.3048)
			(stroke
				(width 0.1)
				(type default)
			)
			(layer "F.Fab")
		)
		(pad "1" smd circle
			(at -0.40005 0)
			(size 0 0)
			(layers "F.Cu" "F.Mask" "F.Paste")
			(net "P12V_NIC1_CO_IMON_VR")
		)
		(pad "2" smd circle
			(at 0.40005 0)
			(size 0 0)
			(layers "F.Cu" "F.Mask" "F.Paste")
			(net "GND")
		)
	)
	(footprint ""
		(layer "F.Cu")
		(at 459.505812 -550.105834 180)
		(property "Reference" "SCREW_SSD13_2"
			(at -5.6007 -1.402334 0)
			(unlocked yes)
			(layer "B.SilkS")
			(effects
				(font
					(size 0.7874 0.5842)
					(thickness 0.1524)
				)
				(justify mirror)
			)
		)
		(property "Value" ""
			(at 0 0 180)
			(layer "F.Fab")
			(effects
				(font
					(size 1.27 1.27)
				)
			)
		)
		(duplicate_pad_numbers_are_jumpers no)
		(pad "1" thru_hole circle
			(at 0 0 180)
			(size 0.4572 0.4572)
			(drill 0.2032)
			(layers "*.Cu" "*.Mask")
			(remove_unused_layers no)
			(net "Net_9147")
			(clearance 0.127)
			(thermal_gap 0.127)
			(padstack
				(mode front_inner_back)
				(layer "Inner"
					(shape circle)
					(size 0.4572 0.4572)
					(clearance 0.127)
				)
				(layer "B.Cu"
					(shape circle)
					(size 0.508 0.508)
					(clearance 0.1016)
				)
			)
		)
	)
)
